(kicad_pcb
	(version 20241229)
	(generator "pcbnew")
	(generator_version "9.0")
	(general
		(thickness 1.61)
		(legacy_teardrops no)
	)
	(paper "A3")
	(title_block
		(title "SO-DIMM DDR5 Tester")
		(date "2025-11-26")
		(rev "1.3.0")
		(comment 9 "footprints 594-600 of 627")
	)
	(layers
		(0 "F.Cu" signal)
		(4 "In1.Cu" power)
		(6 "In2.Cu" mixed)
		(8 "In3.Cu" power)
		(10 "In4.Cu" mixed)
		(12 "In5.Cu" power)
		(14 "In6.Cu" mixed)
		(16 "In7.Cu" power)
		(18 "In8.Cu" power)
		(20 "In9.Cu" mixed)
		(22 "In10.Cu" power)
		(2 "B.Cu" signal)
		(9 "F.Adhes" user "F.Adhesive")
		(11 "B.Adhes" user "B.Adhesive")
		(13 "F.Paste" user)
		(15 "B.Paste" user)
		(5 "F.SilkS" user "F.Silkscreen")
		(7 "B.SilkS" user "B.Silkscreen")
		(1 "F.Mask" user)
		(3 "B.Mask" user)
		(17 "Dwgs.User" user "User.Drawings")
		(19 "Cmts.User" user "User.Comments")
		(21 "Eco1.User" user "User.Eco1")
		(23 "Eco2.User" user "User.Eco2")
		(25 "Edge.Cuts" user)
		(27 "Margin" user)
		(31 "F.CrtYd" user "F.Courtyard")
		(29 "B.CrtYd" user "B.Courtyard")
		(35 "F.Fab" user)
		(33 "B.Fab" user)
	)
	(footprint "antmicro-footprints:TP_SMD_1mm"
		(layer "B.Cu")
		(at 186.4 190.6 180)
		(property "Reference" "TP29"
			(at 0 0.731898 0)
			(layer "B.SilkS")
			(hide yes)
			(effects
				(font
					(size 0.7 0.7)
					(thickness 0.15)
				)
				(justify left bottom mirror)
			)
		)
		(property "Value" "TP_1mm_SMD"
			(at 0 -1.4 0)
			(layer "B.Fab")
			(effects
				(font
					(size 0.7 0.7)
					(thickness 0.15)
				)
				(justify left bottom mirror)
			)
		)
		(property "MPN" ""
			(at 0 0 0)
			(unlocked yes)
			(layer "B.Fab")
			(hide yes)
			(effects
				(font
					(size 1 1)
					(thickness 0.15)
				)
				(justify mirror)
			)
		)
		(property "Manufacturer" ""
			(at 0 0 0)
			(unlocked yes)
			(layer "B.Fab")
			(hide yes)
			(effects
				(font
					(size 1 1)
					(thickness 0.15)
				)
				(justify mirror)
			)
		)
		(property "Author" "Antmicro"
			(at 0 0 0)
			(unlocked yes)
			(layer "B.Fab")
			(hide yes)
			(effects
				(font
					(size 1 1)
					(thickness 0.15)
				)
				(justify mirror)
			)
		)
		(property "License" "Apache-2.0"
			(at 0 0 0)
			(unlocked yes)
			(layer "B.Fab")
			(hide yes)
			(effects
				(font
					(size 1 1)
					(thickness 0.15)
				)
				(justify mirror)
			)
		)
		(sheetname "/Supply/")
		(sheetfile "supply.kicad_sch")
		(attr exclude_from_pos_files)
		(fp_circle
			(center 0 0)
			(end 0.6 0)
			(stroke
				(width 0.05)
				(type default)
			)
			(fill no)
			(layer "B.CrtYd")
		)
		(fp_text user "Author: Antmicro"
			(at -0.5 -4 0)
			(layer "B.Fab")
			(effects
				(font
					(size 0.7 0.7)
					(thickness 0.15)
				)
				(justify left bottom mirror)
			)
		)
		(fp_text user "${REFERENCE}"
			(at -0.5 -2.8 0)
			(layer "B.Fab")
			(effects
				(font
					(size 0.7 0.7)
					(thickness 0.15)
				)
				(justify left bottom mirror)
			)
		)
		(fp_text user "License: Apache-2.0"
			(at -0.5 -5.2 0)
			(layer "B.Fab")
			(effects
				(font
					(size 0.7 0.7)
					(thickness 0.15)
				)
				(justify left bottom mirror)
			)
		)
		(pad "1" smd circle
			(at 0 0 180)
			(size 1 1)
			(layers "B.Cu" "B.Mask")
			(net 64 "/Supply/1V7")
			(pinfunction "1")
			(pintype "passive")
		)
	)
	(footprint "antmicro-footprints:R_0402_1005Metric"
		(layer "B.Cu")
		(at 180.8 200.4 180)
		(descr "Resistor SMD 0402")
		(tags "resistor SMD 0402")
		(property "Reference" "R174"
			(at -3.95 -0.5 0)
			(layer "B.SilkS")
			(effects
				(font
					(size 0.7 0.7)
					(thickness 0.15)
				)
				(justify left bottom mirror)
			)
		)
		(property "Value" "R_0R_0402"
			(at -1.011843 -1.772047 0)
			(layer "B.Fab")
			(effects
				(font
					(size 0.7 0.7)
					(thickness 0.15)
				)
				(justify left bottom mirror)
			)
		)
		(property "Datasheet" "https://industrial.panasonic.com/cdbs/www-data/pdf/RDA0000/AOA0000C301.pdf"
			(at 0 0 180)
			(layer "F.Fab")
			(hide yes)
			(effects
				(font
					(size 1.27 1.27)
					(thickness 0.15)
				)
			)
		)
		(property "Author" "Antmicro"
			(at 361.6 400.8 0)
			(layer "B.Fab")
			(hide yes)
			(effects
				(font
					(size 1 1)
					(thickness 0.15)
				)
				(justify mirror)
			)
		)
		(property "Current" "1A"
			(at 361.6 400.8 0)
			(layer "B.Fab")
			(hide yes)
			(effects
				(font
					(size 1 1)
					(thickness 0.15)
				)
				(justify mirror)
			)
		)
		(property "License" "Apache-2.0"
			(at 361.6 400.8 0)
			(layer "B.Fab")
			(hide yes)
			(effects
				(font
					(size 1 1)
					(thickness 0.15)
				)
				(justify mirror)
			)
		)
		(property "MPN" "ERJ2GE0R00X"
			(at 361.6 400.8 0)
			(layer "B.Fab")
			(hide yes)
			(effects
				(font
					(size 1 1)
					(thickness 0.15)
				)
				(justify mirror)
			)
		)
		(property "Manufacturer" "Panasonic"
			(at 361.6 400.8 0)
			(layer "B.Fab")
			(hide yes)
			(effects
				(font
					(size 1 1)
					(thickness 0.15)
				)
				(justify mirror)
			)
		)
		(property "Tolerance" ""
			(at 361.6 400.8 0)
			(layer "B.Fab")
			(hide yes)
			(effects
				(font
					(size 1 1)
					(thickness 0.15)
				)
				(justify mirror)
			)
		)
		(property "Val" "0R"
			(at 361.6 400.8 0)
			(layer "B.Fab")
			(hide yes)
			(effects
				(font
					(size 1 1)
					(thickness 0.15)
				)
				(justify mirror)
			)
		)
		(sheetname "/I^{2}C/")
		(sheetfile "i2c.kicad_sch")
		(attr exclude_from_pos_files exclude_from_bom dnp)
		(fp_rect
			(start -0.93 0.47)
			(end 0.93 -0.47)
			(stroke
				(width 0.05)
				(type solid)
			)
			(fill no)
			(layer "B.CrtYd")
		)
		(fp_rect
			(start -0.5 0.25)
			(end 0.5 -0.25)
			(stroke
				(width 0.15)
				(type solid)
			)
			(fill no)
			(layer "B.Fab")
		)
		(pad "1" smd roundrect
			(at -0.485 0 180)
			(size 0.59 0.64)
			(layers "B.Cu" "B.Mask" "B.Paste")
			(roundrect_rratio 0.25)
			(net 690 "/I^{2}C/PWR.SDA")
			(pintype "passive")
		)
		(pad "2" smd roundrect
			(at 0.485 0 180)
			(size 0.59 0.64)
			(layers "B.Cu" "B.Mask" "B.Paste")
			(roundrect_rratio 0.25)
			(net 683 "/FPGA bank 14/FPGA_DDR.SDA")
			(pintype "passive")
		)
	)
	(footprint "antmicro-footprints:C_0805_2012Metric"
		(layer "B.Cu")
		(at 136.000501 174.801)
		(descr "Capacitor SMD 0805")
		(tags "capacitor SMD 0805")
		(property "Reference" "C54"
			(at -2.10551 1.198678 0)
			(layer "B.SilkS")
			(hide yes)
			(effects
				(font
					(size 0.7 0.7)
					(thickness 0.15)
				)
				(justify right bottom mirror)
			)
		)
		(property "Value" "C_100u_0805"
			(at -2.055717 -1.963152 0)
			(layer "B.Fab")
			(effects
				(font
					(size 0.7 0.7)
					(thickness 0.15)
				)
				(justify right bottom mirror)
			)
		)
		(property "Datasheet" "https://www.murata.com/products/productdetail?partno=GRM21BR60J107ME15%23"
			(at 0 0 0)
			(layer "F.Fab")
			(hide yes)
			(effects
				(font
					(size 1.27 1.27)
					(thickness 0.15)
				)
			)
		)
		(property "Author" "Antmicro"
			(at 0 0 0)
			(layer "B.Fab")
			(hide yes)
			(effects
				(font
					(size 1 1)
					(thickness 0.15)
				)
				(justify mirror)
			)
		)
		(property "Dielectric" ""
			(at 0 0 0)
			(layer "B.Fab")
			(hide yes)
			(effects
				(font
					(size 1 1)
					(thickness 0.15)
				)
				(justify mirror)
			)
		)
		(property "License" "Apache-2.0"
			(at 0 0 0)
			(layer "B.Fab")
			(hide yes)
			(effects
				(font
					(size 1 1)
					(thickness 0.15)
				)
				(justify mirror)
			)
		)
		(property "MPN" "GRM21BR60J107ME15L"
			(at 0 0 0)
			(layer "B.Fab")
			(hide yes)
			(effects
				(font
					(size 1 1)
					(thickness 0.15)
				)
				(justify mirror)
			)
		)
		(property "Manufacturer" "Murata"
			(at 0 0 0)
			(layer "B.Fab")
			(hide yes)
			(effects
				(font
					(size 1 1)
					(thickness 0.15)
				)
				(justify mirror)
			)
		)
		(property "Val" "100u"
			(at 0 0 0)
			(layer "B.Fab")
			(hide yes)
			(effects
				(font
					(size 1 1)
					(thickness 0.15)
				)
				(justify mirror)
			)
		)
		(property "Voltage" ""
			(at 0 0 0)
			(layer "B.Fab")
			(hide yes)
			(effects
				(font
					(size 1 1)
					(thickness 0.15)
				)
				(justify mirror)
			)
		)
		(sheetname "/FPGA power/")
		(sheetfile "fpga-power.kicad_sch")
		(attr smd)
		(fp_line
			(start -0.3 -0.8)
			(end 0.3 -0.8)
			(stroke
				(width 0.15)
				(type solid)
			)
			(layer "B.SilkS")
		)
		(fp_line
			(start -0.3 0.8)
			(end 0.3 0.8)
			(stroke
				(width 0.15)
				(type solid)
			)
			(layer "B.SilkS")
		)
		(fp_rect
			(start -1.9 0.93)
			(end 1.9 -0.93)
			(stroke
				(width 0.05)
				(type solid)
			)
			(fill no)
			(layer "B.CrtYd")
		)
		(fp_rect
			(start -0.95 0.675)
			(end 0.95 -0.675)
			(stroke
				(width 0.15)
				(type solid)
			)
			(fill no)
			(layer "B.Fab")
		)
		(pad "1" smd rect
			(at -1.05 0)
			(size 1.2 1.2)
			(layers "B.Cu" "B.Mask" "B.Paste")
			(net 1 "GND")
			(pintype "passive")
		)
		(pad "2" smd rect
			(at 1.05 0)
			(size 1.2 1.2)
			(layers "B.Cu" "B.Mask" "B.Paste")
			(net 227 "+1V0")
			(pintype "passive")
		)
	)
	(footprint "antmicro-footprints:C_0402_1005Metric"
		(layer "B.Cu")
		(at 128.5 204.775 90)
		(descr "Capacitor SMD 0402")
		(tags "capacitor SMD 0402")
		(property "Reference" "C222"
			(at 0 0.699 270)
			(layer "B.SilkS")
			(hide yes)
			(effects
				(font
					(size 0.7 0.7)
					(thickness 0.15)
				)
				(justify left bottom mirror)
			)
		)
		(property "Value" "C_100n_0402"
			(at -1.022927 -2.155213 270)
			(layer "B.Fab")
			(effects
				(font
					(size 0.7 0.7)
					(thickness 0.15)
				)
				(justify left bottom mirror)
			)
		)
		(property "Datasheet" "https://www.murata.com/products/productdetail?partno=GRM155R61H104KE14%23"
			(at 0 0 90)
			(layer "F.Fab")
			(hide yes)
			(effects
				(font
					(size 1.27 1.27)
					(thickness 0.15)
				)
			)
		)
		(property "Author" "Antmicro"
			(at 333.275 76.275 0)
			(layer "B.Fab")
			(hide yes)
			(effects
				(font
					(size 1 1)
					(thickness 0.15)
				)
				(justify mirror)
			)
		)
		(property "Dielectric" "X5R"
			(at 333.275 76.275 0)
			(layer "B.Fab")
			(hide yes)
			(effects
				(font
					(size 1 1)
					(thickness 0.15)
				)
				(justify mirror)
			)
		)
		(property "License" "Apache-2.0"
			(at 333.275 76.275 0)
			(layer "B.Fab")
			(hide yes)
			(effects
				(font
					(size 1 1)
					(thickness 0.15)
				)
				(justify mirror)
			)
		)
		(property "MPN" "GRM155R61H104KE14D"
			(at 333.275 76.275 0)
			(layer "B.Fab")
			(hide yes)
			(effects
				(font
					(size 1 1)
					(thickness 0.15)
				)
				(justify mirror)
			)
		)
		(property "Manufacturer" "Murata"
			(at 333.275 76.275 0)
			(layer "B.Fab")
			(hide yes)
			(effects
				(font
					(size 1 1)
					(thickness 0.15)
				)
				(justify mirror)
			)
		)
		(property "Val" "100n"
			(at 333.275 76.275 0)
			(layer "B.Fab")
			(hide yes)
			(effects
				(font
					(size 1 1)
					(thickness 0.15)
				)
				(justify mirror)
			)
		)
		(property "Voltage" "50V"
			(at 333.275 76.275 0)
			(layer "B.Fab")
			(hide yes)
			(effects
				(font
					(size 1 1)
					(thickness 0.15)
				)
				(justify mirror)
			)
		)
		(sheetname "/FPGA MGT Interface/")
		(sheetfile "fpga-mgt.kicad_sch")
		(attr smd)
		(fp_rect
			(start -0.9659 0.481258)
			(end 0.9649 -0.458742)
			(stroke
				(width 0.05)
				(type solid)
			)
			(fill no)
			(layer "B.CrtYd")
		)
		(fp_line
			(start 0.499 -0.248)
			(end -0.499 -0.248)
			(stroke
				(width 0.15)
				(type solid)
			)
			(layer "B.Fab")
		)
		(fp_line
			(start -0.499 -0.248)
			(end -0.499 0.25)
			(stroke
				(width 0.15)
				(type solid)
			)
			(layer "B.Fab")
		)
		(fp_line
			(start 0.499 0.25)
			(end 0.499 -0.248)
			(stroke
				(width 0.15)
				(type solid)
			)
			(layer "B.Fab")
		)
		(fp_line
			(start -0.499 0.25)
			(end 0.499 0.25)
			(stroke
				(width 0.15)
				(type solid)
			)
			(layer "B.Fab")
		)
		(pad "1" smd roundrect
			(at -0.484 0 90)
			(size 0.59 0.64)
			(layers "B.Cu" "B.Mask" "B.Paste")
			(roundrect_rratio 0.25)
			(net 12 "/FPGA MGT Interface/PCIE.CLK_P")
			(pintype "passive")
		)
		(pad "2" smd roundrect
			(at 0.484 0 90)
			(size 0.59 0.64)
			(layers "B.Cu" "B.Mask" "B.Paste")
			(roundrect_rratio 0.25)
			(net 13 "/FPGA MGT Interface/GTR_REFCLK0_P")
			(pintype "passive")
		)
	)
	(footprint "antmicro-footprints:TP_SMD_1mm"
		(layer "B.Cu")
		(at 193.6 174.1 180)
		(property "Reference" "TP32"
			(at 0 0.731898 0)
			(layer "B.SilkS")
			(hide yes)
			(effects
				(font
					(size 0.7 0.7)
					(thickness 0.15)
				)
				(justify left bottom mirror)
			)
		)
		(property "Value" "TP_1mm_SMD"
			(at 0 -1.4 0)
			(layer "B.Fab")
			(effects
				(font
					(size 0.7 0.7)
					(thickness 0.15)
				)
				(justify left bottom mirror)
			)
		)
		(property "MPN" ""
			(at 0 0 0)
			(unlocked yes)
			(layer "B.Fab")
			(hide yes)
			(effects
				(font
					(size 1 1)
					(thickness 0.15)
				)
				(justify mirror)
			)
		)
		(property "Manufacturer" ""
			(at 0 0 0)
			(unlocked yes)
			(layer "B.Fab")
			(hide yes)
			(effects
				(font
					(size 1 1)
					(thickness 0.15)
				)
				(justify mirror)
			)
		)
		(property "Author" "Antmicro"
			(at 0 0 0)
			(unlocked yes)
			(layer "B.Fab")
			(hide yes)
			(effects
				(font
					(size 1 1)
					(thickness 0.15)
				)
				(justify mirror)
			)
		)
		(property "License" "Apache-2.0"
			(at 0 0 0)
			(unlocked yes)
			(layer "B.Fab")
			(hide yes)
			(effects
				(font
					(size 1 1)
					(thickness 0.15)
				)
				(justify mirror)
			)
		)
		(sheetname "/Supply/")
		(sheetfile "supply.kicad_sch")
		(attr exclude_from_pos_files)
		(fp_circle
			(center 0 0)
			(end 0.6 0)
			(stroke
				(width 0.05)
				(type default)
			)
			(fill no)
			(layer "B.CrtYd")
		)
		(fp_text user "License: Apache-2.0"
			(at -0.5 -5.2 0)
			(layer "B.Fab")
			(effects
				(font
					(size 0.7 0.7)
					(thickness 0.15)
				)
				(justify left bottom mirror)
			)
		)
		(fp_text user "${REFERENCE}"
			(at -0.5 -2.8 0)
			(layer "B.Fab")
			(effects
				(font
					(size 0.7 0.7)
					(thickness 0.15)
				)
				(justify left bottom mirror)
			)
		)
		(fp_text user "Author: Antmicro"
			(at -0.5 -4 0)
			(layer "B.Fab")
			(effects
				(font
					(size 0.7 0.7)
					(thickness 0.15)
				)
				(justify left bottom mirror)
			)
		)
		(pad "1" smd circle
			(at 0 0 180)
			(size 1 1)
			(layers "B.Cu" "B.Mask")
			(net 199 "+1V2")
			(pinfunction "1")
			(pintype "passive")
		)
	)
	(footprint "antmicro-footprints:R_0402_1005Metric"
		(layer "B.Cu")
		(at 140.302001 159.125 -90)
		(descr "Resistor SMD 0402")
		(tags "resistor SMD 0402")
		(property "Reference" "R131"
			(at -1.122484 0.772697 90)
			(layer "B.SilkS")
			(hide yes)
			(effects
				(font
					(size 0.7 0.7)
					(thickness 0.15)
				)
				(justify left bottom mirror)
			)
		)
		(property "Value" "R_0R_0402"
			(at -1.011843 -1.772047 90)
			(layer "B.Fab")
			(effects
				(font
					(size 0.7 0.7)
					(thickness 0.15)
				)
				(justify left bottom mirror)
			)
		)
		(property "Datasheet" "https://industrial.panasonic.com/cdbs/www-data/pdf/RDA0000/AOA0000C301.pdf"
			(at 0 0 270)
			(layer "F.Fab")
			(hide yes)
			(effects
				(font
					(size 1.27 1.27)
					(thickness 0.15)
				)
			)
		)
		(property "Author" "Antmicro"
			(at -18.822999 299.427001 0)
			(layer "B.Fab")
			(hide yes)
			(effects
				(font
					(size 1 1)
					(thickness 0.15)
				)
				(justify mirror)
			)
		)
		(property "Current" "1A"
			(at -18.822999 299.427001 0)
			(layer "B.Fab")
			(hide yes)
			(effects
				(font
					(size 1 1)
					(thickness 0.15)
				)
				(justify mirror)
			)
		)
		(property "License" "Apache-2.0"
			(at -18.822999 299.427001 0)
			(layer "B.Fab")
			(hide yes)
			(effects
				(font
					(size 1 1)
					(thickness 0.15)
				)
				(justify mirror)
			)
		)
		(property "MPN" "ERJ2GE0R00X"
			(at -18.822999 299.427001 0)
			(layer "B.Fab")
			(hide yes)
			(effects
				(font
					(size 1 1)
					(thickness 0.15)
				)
				(justify mirror)
			)
		)
		(property "Manufacturer" "Panasonic"
			(at -18.822999 299.427001 0)
			(layer "B.Fab")
			(hide yes)
			(effects
				(font
					(size 1 1)
					(thickness 0.15)
				)
				(justify mirror)
			)
		)
		(property "Tolerance" ""
			(at -18.822999 299.427001 0)
			(layer "B.Fab")
			(hide yes)
			(effects
				(font
					(size 1 1)
					(thickness 0.15)
				)
				(justify mirror)
			)
		)
		(property "Val" "0R"
			(at -18.822999 299.427001 0)
			(layer "B.Fab")
			(hide yes)
			(effects
				(font
					(size 1 1)
					(thickness 0.15)
				)
				(justify mirror)
			)
		)
		(sheetname "/FPGA banks HP/")
		(sheetfile "fpga-banks-32-34.kicad_sch")
		(attr exclude_from_bom)
		(fp_rect
			(start -0.93 0.47)
			(end 0.93 -0.47)
			(stroke
				(width 0.05)
				(type solid)
			)
			(fill no)
			(layer "B.CrtYd")
		)
		(fp_rect
			(start -0.5 0.25)
			(end 0.5 -0.25)
			(stroke
				(width 0.15)
				(type solid)
			)
			(fill no)
			(layer "B.Fab")
		)
		(pad "1" smd roundrect
			(at -0.485 0 270)
			(size 0.59 0.64)
			(layers "B.Cu" "B.Mask" "B.Paste")
			(roundrect_rratio 0.25)
			(net 36 "DAC_VREF")
			(pintype "passive")
		)
		(pad "2" smd roundrect
			(at 0.485 0 270)
			(size 0.59 0.64)
			(layers "B.Cu" "B.Mask" "B.Paste")
			(roundrect_rratio 0.25)
			(net 10 "/FPGA banks HP/VREF")
			(pintype "passive")
		)
	)
	(footprint "antmicro-footprints:C_0402_1005Metric"
		(layer "B.Cu")
		(at 88.806897 137.413487 90)
		(descr "Capacitor SMD 0402")
		(tags "capacitor SMD 0402")
		(property "Reference" "C137"
			(at 0 0.699 270)
			(layer "B.SilkS")
			(hide yes)
			(effects
				(font
					(size 0.7 0.7)
					(thickness 0.15)
				)
				(justify left bottom mirror)
			)
		)
		(property "Value" "C_100n_0402"
			(at -1.022927 -2.155213 270)
			(layer "B.Fab")
			(effects
				(font
					(size 0.7 0.7)
					(thickness 0.15)
				)
				(justify left bottom mirror)
			)
		)
		(property "Datasheet" "https://www.murata.com/products/productdetail?partno=GRM155R61H104KE14%23"
			(at 0 0 90)
			(layer "F.Fab")
			(hide yes)
			(effects
				(font
					(size 1.27 1.27)
					(thickness 0.15)
				)
			)
		)
		(property "Author" "Antmicro"
			(at 226.220384 48.60659 0)
			(layer "B.Fab")
			(hide yes)
			(effects
				(font
					(size 1 1)
					(thickness 0.15)
				)
				(justify mirror)
			)
		)
		(property "Dielectric" "X5R"
			(at 226.220384 48.60659 0)
			(layer "B.Fab")
			(hide yes)
			(effects
				(font
					(size 1 1)
					(thickness 0.15)
				)
				(justify mirror)
			)
		)
		(property "License" "Apache-2.0"
			(at 226.220384 48.60659 0)
			(layer "B.Fab")
			(hide yes)
			(effects
				(font
					(size 1 1)
					(thickness 0.15)
				)
				(justify mirror)
			)
		)
		(property "MPN" "GRM155R61H104KE14D"
			(at 226.220384 48.60659 0)
			(layer "B.Fab")
			(hide yes)
			(effects
				(font
					(size 1 1)
					(thickness 0.15)
				)
				(justify mirror)
			)
		)
		(property "Manufacturer" "Murata"
			(at 226.220384 48.60659 0)
			(layer "B.Fab")
			(hide yes)
			(effects
				(font
					(size 1 1)
					(thickness 0.15)
				)
				(justify mirror)
			)
		)
		(property "Val" "100n"
			(at 226.220384 48.60659 0)
			(layer "B.Fab")
			(hide yes)
			(effects
				(font
					(size 1 1)
					(thickness 0.15)
				)
				(justify mirror)
			)
		)
		(property "Voltage" "50V"
			(at 226.220384 48.60659 0)
			(layer "B.Fab")
			(hide yes)
			(effects
				(font
					(size 1 1)
					(thickness 0.15)
				)
				(justify mirror)
			)
		)
		(sheetname "/Ethernet/")
		(sheetfile "ethernet.kicad_sch")
		(attr smd)
		(fp_rect
			(start -0.9659 0.481258)
			(end 0.9649 -0.458742)
			(stroke
				(width 0.05)
				(type solid)
			)
			(fill no)
			(layer "B.CrtYd")
		)
		(fp_line
			(start 0.499 -0.248)
			(end -0.499 -0.248)
			(stroke
				(width 0.15)
				(type solid)
			)
			(layer "B.Fab")
		)
		(fp_line
			(start -0.499 -0.248)
			(end -0.499 0.25)
			(stroke
				(width 0.15)
				(type solid)
			)
			(layer "B.Fab")
		)
		(fp_line
			(start 0.499 0.25)
			(end 0.499 -0.248)
			(stroke
				(width 0.15)
				(type solid)
			)
			(layer "B.Fab")
		)
		(fp_line
			(start -0.499 0.25)
			(end 0.499 0.25)
			(stroke
				(width 0.15)
				(type solid)
			)
			(layer "B.Fab")
		)
		(pad "1" smd roundrect
			(at -0.484 0 90)
			(size 0.59 0.64)
			(layers "B.Cu" "B.Mask" "B.Paste")
			(roundrect_rratio 0.25)
			(net 1 "GND")
			(pintype "passive")
		)
		(pad "2" smd roundrect
			(at 0.484 0 90)
			(size 0.59 0.64)
			(layers "B.Cu" "B.Mask" "B.Paste")
			(roundrect_rratio 0.25)
			(net 215 "Net-(C137-Pad2)")
			(pintype "passive")
		)
	)
)
